# S9S_MB_2U (Grand Teton) — schematic netlist excerpt (pin names and nets, part order shuffled) for the footprints in the layout excerpt that follows; sources: Cadence DE-HDL packaged netlist, KiCad conversion of 03242023_DA0F0TMBIJ0_F0T_Motherboard_J_brd_V01_OCP.brd

R2936  Q_RES  100K 1% EMPTY  pkg 0402LF  page 151 : A = P3V3_AUX ; B = FM_GPU_PWR_EN_R
PC1648  Q_CAP  100NF 50V 10% X7R  pkg C0402  page 258 : A = P12V_AUX ; B = GND

(kicad_pcb
	(version 20260206)
	(generator "pcbnew")
	(generator_version "10.0")
	(general
		(thickness 1.6)
		(legacy_teardrops no)
	)
	(paper "A4")
	(title_block
		(title "03242023_DA0F0TMBIJ0_F0T_Motherboard_J_brd_V01_OCP.brd")
		(comment 1 "Grand Teton / footprints 3127-3128 of 6105")
	)
	(layers
		(0 "F.Cu" signal "TOP")
		(4 "In1.Cu" signal "GND")
		(6 "In2.Cu" signal "IN1")
		(8 "In3.Cu" signal "GND1")
		(10 "In4.Cu" signal "IN2")
		(12 "In5.Cu" signal "GND2")
		(14 "In6.Cu" signal "IN3")
		(16 "In7.Cu" signal "GND3")
		(18 "In8.Cu" signal "VCC")
		(20 "In9.Cu" signal "VCC1")
		(22 "In10.Cu" signal "GND4")
		(24 "In11.Cu" signal "IN4")
		(26 "In12.Cu" signal "GND5")
		(28 "In13.Cu" signal "IN5")
		(30 "In14.Cu" signal "GND6")
		(32 "In15.Cu" signal "IN6")
		(34 "In16.Cu" signal "GND7")
		(2 "B.Cu" signal "BOTTOM")
		(9 "F.Adhes" user "F.Adhesive")
		(11 "B.Adhes" user "B.Adhesive")
		(13 "F.Paste" user "Package Geometry/Pastemask Top")
		(15 "B.Paste" user "Package Geometry/Pastemask Bottom")
		(5 "F.SilkS" user "Ref Des/Silkscreen Top")
		(7 "B.SilkS" user "Ref Des/Silkscreen Bottom")
		(1 "F.Mask" user "Board Geometry/Soldermask Top")
		(3 "B.Mask" user "Board Geometry/Soldermask Bottom")
		(17 "Dwgs.User" user "User.Drawings")
		(19 "Cmts.User" user "User.Comments")
		(21 "Eco1.User" user "User.Eco1")
		(23 "Eco2.User" user "User.Eco2")
		(25 "Edge.Cuts" user "Board Geometry/Outline")
		(27 "Margin" user)
		(31 "F.CrtYd" user "Package Geometry/Place Bound Top")
		(29 "B.CrtYd" user "Package Geometry/Place Bound Bottom")
		(35 "F.Fab" user "Ref Des/Assembly Top")
		(33 "B.Fab" user "Ref Des/Assembly Bottom")
	)
	(footprint ""
		(layer "F.Cu")
		(at 463.82305 -382.610614 90)
		(property "Reference" "PC1648"
			(at 0 0 90)
			(layer "F.SilkS")
			(hide yes)
			(effects
				(font
					(size 1.27 1.27)
				)
			)
		)
		(property "Value" ""
			(at 0 0 90)
			(layer "F.Fab")
			(effects
				(font
					(size 1.27 1.27)
				)
			)
		)
		(duplicate_pad_numbers_are_jumpers no)
		(fp_line
			(start 0.7874 -0.4064)
			(end 0.7874 0.4064)
			(stroke
				(width 0.1524)
				(type default)
			)
			(layer "F.SilkS")
		)
		(fp_line
			(start -0.7874 -0.4064)
			(end 0.7874 -0.4064)
			(stroke
				(width 0.1524)
				(type default)
			)
			(layer "F.SilkS")
		)
		(fp_line
			(start 0.7874 0.4064)
			(end -0.7874 0.4064)
			(stroke
				(width 0.1524)
				(type default)
			)
			(layer "F.SilkS")
		)
		(fp_line
			(start -0.7874 0.4064)
			(end -0.7874 -0.4064)
			(stroke
				(width 0.1524)
				(type default)
			)
			(layer "F.SilkS")
		)
		(fp_line
			(start -0.12065 -0.305054)
			(end -0.12065 -0.2794)
			(stroke
				(width 0.1)
				(type default)
			)
			(layer "F.Fab")
		)
		(fp_line
			(start -0.67945 -0.305054)
			(end -0.12065 -0.305054)
			(stroke
				(width 0.1)
				(type default)
			)
			(layer "F.Fab")
		)
		(fp_line
			(start 0.67945 -0.3048)
			(end 0.67945 0.3048)
			(stroke
				(width 0.1)
				(type default)
			)
			(layer "F.Fab")
		)
		(fp_line
			(start 0.12065 -0.3048)
			(end 0.67945 -0.3048)
			(stroke
				(width 0.1)
				(type default)
			)
			(layer "F.Fab")
		)
		(fp_line
			(start 0.12065 -0.2794)
			(end 0.12065 -0.3048)
			(stroke
				(width 0.1)
				(type default)
			)
			(layer "F.Fab")
		)
		(fp_line
			(start -0.12065 -0.2794)
			(end 0.12065 -0.2794)
			(stroke
				(width 0.1)
				(type default)
			)
			(layer "F.Fab")
		)
		(fp_line
			(start 0.120396 0.2794)
			(end -0.12065 0.2794)
			(stroke
				(width 0.1)
				(type default)
			)
			(layer "F.Fab")
		)
		(fp_line
			(start -0.12065 0.2794)
			(end -0.12065 0.3048)
			(stroke
				(width 0.1)
				(type default)
			)
			(layer "F.Fab")
		)
		(fp_line
			(start 0.67945 0.3048)
			(end 0.120396 0.3048)
			(stroke
				(width 0.1)
				(type default)
			)
			(layer "F.Fab")
		)
		(fp_line
			(start 0.120396 0.3048)
			(end 0.120396 0.2794)
			(stroke
				(width 0.1)
				(type default)
			)
			(layer "F.Fab")
		)
		(fp_line
			(start -0.12065 0.3048)
			(end -0.67945 0.3048)
			(stroke
				(width 0.1)
				(type default)
			)
			(layer "F.Fab")
		)
		(fp_line
			(start -0.67945 0.3048)
			(end -0.67945 -0.305054)
			(stroke
				(width 0.1)
				(type default)
			)
			(layer "F.Fab")
		)
		(pad "1" smd circle
			(at -0.40005 0 90)
			(size 0 0)
			(layers "F.Cu" "F.Mask" "F.Paste")
			(net "P12V_AUX")
		)
		(pad "2" smd circle
			(at 0.40005 0 90)
			(size 0 0)
			(layers "F.Cu" "F.Mask" "F.Paste")
			(net "GND")
		)
	)
	(footprint ""
		(layer "F.Cu")
		(at 120.36044 -426.075348 180)
		(property "Reference" "R2936"
			(at 0 0 180)
			(layer "F.SilkS")
			(hide yes)
			(effects
				(font
					(size 1.27 1.27)
				)
			)
		)
		(property "Value" ""
			(at 0 0 180)
			(layer "F.Fab")
			(effects
				(font
					(size 1.27 1.27)
				)
			)
		)
		(duplicate_pad_numbers_are_jumpers no)
		(fp_line
			(start 0.7874 0.4064)
			(end -0.7874 0.4064)
			(stroke
				(width 0.1524)
				(type default)
			)
			(layer "F.SilkS")
		)
		(fp_line
			(start 0.7874 -0.4064)
			(end 0.7874 0.4064)
			(stroke
				(width 0.1524)
				(type default)
			)
			(layer "F.SilkS")
		)
		(fp_line
			(start -0.7874 0.4064)
			(end -0.7874 -0.4064)
			(stroke
				(width 0.1524)
				(type default)
			)
			(layer "F.SilkS")
		)
		(fp_line
			(start -0.7874 -0.4064)
			(end 0.7874 -0.4064)
			(stroke
				(width 0.1524)
				(type default)
			)
			(layer "F.SilkS")
		)
		(fp_line
			(start 0.67945 0.3048)
			(end 0.120396 0.3048)
			(stroke
				(width 0.1)
				(type default)
			)
			(layer "F.Fab")
		)
		(fp_line
			(start 0.67945 -0.3048)
			(end 0.67945 0.3048)
			(stroke
				(width 0.1)
				(type default)
			)
			(layer "F.Fab")
		)
		(fp_line
			(start 0.12065 -0.2794)
			(end 0.12065 -0.3048)
			(stroke
				(width 0.1)
				(type default)
			)
			(layer "F.Fab")
		)
		(fp_line
			(start 0.12065 -0.3048)
			(end 0.67945 -0.3048)
			(stroke
				(width 0.1)
				(type default)
			)
			(layer "F.Fab")
		)
		(fp_line
			(start 0.120396 0.3048)
			(end 0.120396 0.2794)
			(stroke
				(width 0.1)
				(type default)
			)
			(layer "F.Fab")
		)
		(fp_line
			(start 0.120396 0.2794)
			(end -0.12065 0.2794)
			(stroke
				(width 0.1)
				(type default)
			)
			(layer "F.Fab")
		)
		(fp_line
			(start -0.12065 0.3048)
			(end -0.67945 0.3048)
			(stroke
				(width 0.1)
				(type default)
			)
			(layer "F.Fab")
		)
		(fp_line
			(start -0.12065 0.2794)
			(end -0.12065 0.3048)
			(stroke
				(width 0.1)
				(type default)
			)
			(layer "F.Fab")
		)
		(fp_line
			(start -0.12065 -0.2794)
			(end 0.12065 -0.2794)
			(stroke
				(width 0.1)
				(type default)
			)
			(layer "F.Fab")
		)
		(fp_line
			(start -0.12065 -0.305054)
			(end -0.12065 -0.2794)
			(stroke
				(width 0.1)
				(type default)
			)
			(layer "F.Fab")
		)
		(fp_line
			(start -0.67945 0.3048)
			(end -0.67945 -0.305054)
			(stroke
				(width 0.1)
				(type default)
			)
			(layer "F.Fab")
		)
		(fp_line
			(start -0.67945 -0.305054)
			(end -0.12065 -0.305054)
			(stroke
				(width 0.1)
				(type default)
			)
			(layer "F.Fab")
		)
		(pad "1" smd circle
			(at -0.40005 0 180)
			(size 0 0)
			(layers "F.Cu" "F.Mask" "F.Paste")
			(net "P3V3_AUX")
		)
		(pad "2" smd circle
			(at 0.40005 0 180)
			(size 0 0)
			(layers "F.Cu" "F.Mask" "F.Paste")
			(net "FM_GPU_PWR_EN_R")
		)
	)
)
